(kicad_pcb
	(version 20260206)
	(generator "pcbnew")
	(generator_version "10.0")
	(general
		(thickness 1.6)
		(legacy_teardrops no)
	)
	(paper "A4")
	(title_block
		(title "03242023_DA0F0TMBIJ0_F0T_Motherboard_J_brd_V01_OCP.brd")
		(comment 1 "Grand Teton / footprints 5151-5156 of 6105")
	)
	(layers
		(0 "F.Cu" signal "TOP")
		(4 "In1.Cu" signal "GND")
		(6 "In2.Cu" signal "IN1")
		(8 "In3.Cu" signal "GND1")
		(10 "In4.Cu" signal "IN2")
		(12 "In5.Cu" signal "GND2")
		(14 "In6.Cu" signal "IN3")
		(16 "In7.Cu" signal "GND3")
		(18 "In8.Cu" signal "VCC")
		(20 "In9.Cu" signal "VCC1")
		(22 "In10.Cu" signal "GND4")
		(24 "In11.Cu" signal "IN4")
		(26 "In12.Cu" signal "GND5")
		(28 "In13.Cu" signal "IN5")
		(30 "In14.Cu" signal "GND6")
		(32 "In15.Cu" signal "IN6")
		(34 "In16.Cu" signal "GND7")
		(2 "B.Cu" signal "BOTTOM")
		(9 "F.Adhes" user "F.Adhesive")
		(11 "B.Adhes" user "B.Adhesive")
		(13 "F.Paste" user "Package Geometry/Pastemask Top")
		(15 "B.Paste" user "Package Geometry/Pastemask Bottom")
		(5 "F.SilkS" user "Ref Des/Silkscreen Top")
		(7 "B.SilkS" user "Ref Des/Silkscreen Bottom")
		(1 "F.Mask" user "Board Geometry/Soldermask Top")
		(3 "B.Mask" user "Board Geometry/Soldermask Bottom")
		(17 "Dwgs.User" user "User.Drawings")
		(19 "Cmts.User" user "User.Comments")
		(21 "Eco1.User" user "User.Eco1")
		(23 "Eco2.User" user "User.Eco2")
		(25 "Edge.Cuts" user "Board Geometry/Outline")
		(27 "Margin" user)
		(31 "F.CrtYd" user "Package Geometry/Place Bound Top")
		(29 "B.CrtYd" user "Package Geometry/Place Bound Bottom")
		(35 "F.Fab" user "Ref Des/Assembly Top")
		(33 "B.Fab" user "Ref Des/Assembly Bottom")
	)
	(footprint ""
		(layer "B.Cu")
		(at 429.40224 -108.867448 90)
		(property "Reference" "R3785"
			(at 0 0 90)
			(layer "B.SilkS")
			(hide yes)
			(effects
				(font
					(size 1.27 1.27)
				)
				(justify mirror)
			)
		)
		(property "Value" ""
			(at 0 0 90)
			(layer "B.Fab")
			(effects
				(font
					(size 1.27 1.27)
				)
				(justify mirror)
			)
		)
		(duplicate_pad_numbers_are_jumpers no)
		(fp_line
			(start 0.7874 -0.4064)
			(end -0.7874 -0.4064)
			(stroke
				(width 0.1524)
				(type default)
			)
			(layer "B.SilkS")
		)
		(fp_line
			(start -0.7874 -0.4064)
			(end -0.7874 0.4064)
			(stroke
				(width 0.1524)
				(type default)
			)
			(layer "B.SilkS")
		)
		(fp_line
			(start 0.7874 0.4064)
			(end 0.7874 -0.4064)
			(stroke
				(width 0.1524)
				(type default)
			)
			(layer "B.SilkS")
		)
		(fp_line
			(start -0.7874 0.4064)
			(end 0.7874 0.4064)
			(stroke
				(width 0.1524)
				(type default)
			)
			(layer "B.SilkS")
		)
		(fp_line
			(start 0.67945 -0.305054)
			(end 0.12065 -0.305054)
			(stroke
				(width 0.1)
				(type default)
			)
			(layer "B.Fab")
		)
		(fp_line
			(start 0.12065 -0.305054)
			(end 0.12065 -0.2794)
			(stroke
				(width 0.1)
				(type default)
			)
			(layer "B.Fab")
		)
		(fp_line
			(start -0.12065 -0.3048)
			(end -0.67945 -0.3048)
			(stroke
				(width 0.1)
				(type default)
			)
			(layer "B.Fab")
		)
		(fp_line
			(start -0.67945 -0.3048)
			(end -0.67945 0.3048)
			(stroke
				(width 0.1)
				(type default)
			)
			(layer "B.Fab")
		)
		(fp_line
			(start 0.12065 -0.2794)
			(end -0.12065 -0.2794)
			(stroke
				(width 0.1)
				(type default)
			)
			(layer "B.Fab")
		)
		(fp_line
			(start -0.12065 -0.2794)
			(end -0.12065 -0.3048)
			(stroke
				(width 0.1)
				(type default)
			)
			(layer "B.Fab")
		)
		(fp_line
			(start 0.12065 0.2794)
			(end 0.12065 0.3048)
			(stroke
				(width 0.1)
				(type default)
			)
			(layer "B.Fab")
		)
		(fp_line
			(start -0.120396 0.2794)
			(end 0.12065 0.2794)
			(stroke
				(width 0.1)
				(type default)
			)
			(layer "B.Fab")
		)
		(fp_line
			(start 0.67945 0.3048)
			(end 0.67945 -0.305054)
			(stroke
				(width 0.1)
				(type default)
			)
			(layer "B.Fab")
		)
		(fp_line
			(start 0.12065 0.3048)
			(end 0.67945 0.3048)
			(stroke
				(width 0.1)
				(type default)
			)
			(layer "B.Fab")
		)
		(fp_line
			(start -0.120396 0.3048)
			(end -0.120396 0.2794)
			(stroke
				(width 0.1)
				(type default)
			)
			(layer "B.Fab")
		)
		(fp_line
			(start -0.67945 0.3048)
			(end -0.120396 0.3048)
			(stroke
				(width 0.1)
				(type default)
			)
			(layer "B.Fab")
		)
		(pad "1" smd circle
			(at 0.40005 0 270)
			(size 0 0)
			(layers "B.Cu" "B.Mask" "B.Paste")
			(net "P3V3_OCP_UV_1_R1")
		)
		(pad "2" smd circle
			(at -0.40005 0 270)
			(size 0 0)
			(layers "B.Cu" "B.Mask" "B.Paste")
			(net "P3V3_OCP_UV_1")
		)
	)
	(footprint ""
		(layer "B.Cu")
		(at 236.182154 -134.048754 180)
		(property "Reference" "R1022"
			(at 0 0 0)
			(layer "B.SilkS")
			(hide yes)
			(effects
				(font
					(size 1.27 1.27)
				)
				(justify mirror)
			)
		)
		(property "Value" ""
			(at 0 0 0)
			(layer "B.Fab")
			(effects
				(font
					(size 1.27 1.27)
				)
				(justify mirror)
			)
		)
		(duplicate_pad_numbers_are_jumpers no)
		(fp_line
			(start 0.7874 -0.154686)
			(end 0.7874 -0.4064)
			(stroke
				(width 0.1524)
				(type default)
			)
			(layer "B.SilkS")
		)
		(fp_line
			(start 0.7874 -0.4064)
			(end -0.7874 -0.4064)
			(stroke
				(width 0.1524)
				(type default)
			)
			(layer "B.SilkS")
		)
		(fp_line
			(start -0.241046 0.4064)
			(end 0.632714 0.4064)
			(stroke
				(width 0.1524)
				(type default)
			)
			(layer "B.SilkS")
		)
		(fp_line
			(start -0.7874 0.4064)
			(end -0.576326 0.4064)
			(stroke
				(width 0.1524)
				(type default)
			)
			(layer "B.SilkS")
		)
		(fp_line
			(start -0.7874 -0.4064)
			(end -0.7874 0.4064)
			(stroke
				(width 0.1524)
				(type default)
			)
			(layer "B.SilkS")
		)
		(fp_line
			(start 0.67945 0.3048)
			(end 0.67945 -0.305054)
			(stroke
				(width 0.1)
				(type default)
			)
			(layer "B.Fab")
		)
		(fp_line
			(start 0.67945 -0.305054)
			(end 0.12065 -0.305054)
			(stroke
				(width 0.1)
				(type default)
			)
			(layer "B.Fab")
		)
		(fp_line
			(start 0.12065 0.3048)
			(end 0.67945 0.3048)
			(stroke
				(width 0.1)
				(type default)
			)
			(layer "B.Fab")
		)
		(fp_line
			(start 0.12065 0.2794)
			(end 0.12065 0.3048)
			(stroke
				(width 0.1)
				(type default)
			)
			(layer "B.Fab")
		)
		(fp_line
			(start 0.12065 -0.2794)
			(end -0.12065 -0.2794)
			(stroke
				(width 0.1)
				(type default)
			)
			(layer "B.Fab")
		)
		(fp_line
			(start 0.12065 -0.305054)
			(end 0.12065 -0.2794)
			(stroke
				(width 0.1)
				(type default)
			)
			(layer "B.Fab")
		)
		(fp_line
			(start -0.120396 0.3048)
			(end -0.120396 0.2794)
			(stroke
				(width 0.1)
				(type default)
			)
			(layer "B.Fab")
		)
		(fp_line
			(start -0.120396 0.2794)
			(end 0.12065 0.2794)
			(stroke
				(width 0.1)
				(type default)
			)
			(layer "B.Fab")
		)
		(fp_line
			(start -0.12065 -0.2794)
			(end -0.12065 -0.3048)
			(stroke
				(width 0.1)
				(type default)
			)
			(layer "B.Fab")
		)
		(fp_line
			(start -0.12065 -0.3048)
			(end -0.67945 -0.3048)
			(stroke
				(width 0.1)
				(type default)
			)
			(layer "B.Fab")
		)
		(fp_line
			(start -0.67945 0.3048)
			(end -0.120396 0.3048)
			(stroke
				(width 0.1)
				(type default)
			)
			(layer "B.Fab")
		)
		(fp_line
			(start -0.67945 -0.3048)
			(end -0.67945 0.3048)
			(stroke
				(width 0.1)
				(type default)
			)
			(layer "B.Fab")
		)
		(pad "1" smd rect
			(at 0.40005 0 180)
			(size 0.4572 0.508)
			(layers "B.Cu" "B.Mask" "B.Paste")
			(net "CLK_25M_CK440_CPU1_R_DP")
		)
		(pad "2" smd rect
			(at -0.40005 0 180)
			(size 0.4572 0.508)
			(layers "B.Cu" "B.Mask" "B.Paste")
			(net "CLK_25M_NSSC_CPU1_DP")
		)
	)
	(footprint ""
		(layer "B.Cu")
		(at 258.953 -96.738948)
		(property "Reference" "C110"
			(at 0 0 0)
			(layer "B.SilkS")
			(hide yes)
			(effects
				(font
					(size 1.27 1.27)
				)
				(justify mirror)
			)
		)
		(property "Value" ""
			(at 0 0 0)
			(layer "B.Fab")
			(effects
				(font
					(size 1.27 1.27)
				)
				(justify mirror)
			)
		)
		(duplicate_pad_numbers_are_jumpers no)
		(fp_line
			(start -0.7874 -0.4064)
			(end -0.7874 0.4064)
			(stroke
				(width 0.1524)
				(type default)
			)
			(layer "B.SilkS")
		)
		(fp_line
			(start -0.7874 0.4064)
			(end 0.7874 0.4064)
			(stroke
				(width 0.1524)
				(type default)
			)
			(layer "B.SilkS")
		)
		(fp_line
			(start 0.7874 -0.4064)
			(end -0.7874 -0.4064)
			(stroke
				(width 0.1524)
				(type default)
			)
			(layer "B.SilkS")
		)
		(fp_line
			(start 0.7874 0.4064)
			(end 0.7874 -0.4064)
			(stroke
				(width 0.1524)
				(type default)
			)
			(layer "B.SilkS")
		)
		(fp_line
			(start -0.67945 -0.3048)
			(end -0.67945 0.3048)
			(stroke
				(width 0.1)
				(type default)
			)
			(layer "B.Fab")
		)
		(fp_line
			(start -0.67945 0.3048)
			(end -0.120396 0.3048)
			(stroke
				(width 0.1)
				(type default)
			)
			(layer "B.Fab")
		)
		(fp_line
			(start -0.12065 -0.3048)
			(end -0.67945 -0.3048)
			(stroke
				(width 0.1)
				(type default)
			)
			(layer "B.Fab")
		)
		(fp_line
			(start -0.12065 -0.2794)
			(end -0.12065 -0.3048)
			(stroke
				(width 0.1)
				(type default)
			)
			(layer "B.Fab")
		)
		(fp_line
			(start -0.120396 0.2794)
			(end 0.12065 0.2794)
			(stroke
				(width 0.1)
				(type default)
			)
			(layer "B.Fab")
		)
		(fp_line
			(start -0.120396 0.3048)
			(end -0.120396 0.2794)
			(stroke
				(width 0.1)
				(type default)
			)
			(layer "B.Fab")
		)
		(fp_line
			(start 0.12065 -0.305054)
			(end 0.12065 -0.2794)
			(stroke
				(width 0.1)
				(type default)
			)
			(layer "B.Fab")
		)
		(fp_line
			(start 0.12065 -0.2794)
			(end -0.12065 -0.2794)
			(stroke
				(width 0.1)
				(type default)
			)
			(layer "B.Fab")
		)
		(fp_line
			(start 0.12065 0.2794)
			(end 0.12065 0.3048)
			(stroke
				(width 0.1)
				(type default)
			)
			(layer "B.Fab")
		)
		(fp_line
			(start 0.12065 0.3048)
			(end 0.67945 0.3048)
			(stroke
				(width 0.1)
				(type default)
			)
			(layer "B.Fab")
		)
		(fp_line
			(start 0.67945 -0.305054)
			(end 0.12065 -0.305054)
			(stroke
				(width 0.1)
				(type default)
			)
			(layer "B.Fab")
		)
		(fp_line
			(start 0.67945 0.3048)
			(end 0.67945 -0.305054)
			(stroke
				(width 0.1)
				(type default)
			)
			(layer "B.Fab")
		)
		(pad "1" smd circle
			(at 0.40005 0 180)
			(size 0 0)
			(layers "B.Cu" "B.Mask" "B.Paste")
			(net "P3V3_AUX_CLK_GEN_VDD_CK440")
		)
		(pad "2" smd circle
			(at -0.40005 0 180)
			(size 0 0)
			(layers "B.Cu" "B.Mask" "B.Paste")
			(net "GND")
		)
	)
	(footprint ""
		(layer "B.Cu")
		(at 355.826822 -210.19389 180)
		(property "Reference" "C508"
			(at 0 0 0)
			(layer "B.SilkS")
			(hide yes)
			(effects
				(font
					(size 1.27 1.27)
				)
				(justify mirror)
			)
		)
		(property "Value" ""
			(at 0 0 0)
			(layer "B.Fab")
			(effects
				(font
					(size 1.27 1.27)
				)
				(justify mirror)
			)
		)
		(duplicate_pad_numbers_are_jumpers no)
		(fp_line
			(start 1.524 0.762)
			(end 1.524 -0.762)
			(stroke
				(width 0.1524)
				(type default)
			)
			(layer "B.SilkS")
		)
		(fp_line
			(start 1.524 -0.762)
			(end -1.524 -0.762)
			(stroke
				(width 0.1524)
				(type default)
			)
			(layer "B.SilkS")
		)
		(fp_line
			(start -1.524 0.762)
			(end 1.524 0.762)
			(stroke
				(width 0.1524)
				(type default)
			)
			(layer "B.SilkS")
		)
		(fp_line
			(start -1.524 -0.762)
			(end -1.524 0.762)
			(stroke
				(width 0.1524)
				(type default)
			)
			(layer "B.SilkS")
		)
		(fp_line
			(start 1.1049 0.724916)
			(end -1.1049 0.724916)
			(stroke
				(width 0.1)
				(type default)
			)
			(layer "B.Fab")
		)
		(fp_line
			(start 1.1049 -0.724916)
			(end 1.1049 0.724916)
			(stroke
				(width 0.1)
				(type default)
			)
			(layer "B.Fab")
		)
		(fp_line
			(start -1.1049 0.724916)
			(end -1.1049 -0.724916)
			(stroke
				(width 0.1)
				(type default)
			)
			(layer "B.Fab")
		)
		(fp_line
			(start -1.1049 -0.724916)
			(end 1.1049 -0.724916)
			(stroke
				(width 0.1)
				(type default)
			)
			(layer "B.Fab")
		)
		(pad "1" smd rect
			(at 0.889 0 180)
			(size 1.016 1.27)
			(layers "B.Cu" "B.Mask" "B.Paste")
			(net "PVCCFA_EHV_CPU0")
		)
		(pad "2" smd rect
			(at -0.889 0 180)
			(size 1.016 1.27)
			(layers "B.Cu" "B.Mask" "B.Paste")
			(net "GND")
		)
	)
	(footprint ""
		(layer "B.Cu")
		(at 237.844076 -126.513082 180)
		(property "Reference" "R574"
			(at 0 0 0)
			(layer "B.SilkS")
			(hide yes)
			(effects
				(font
					(size 1.27 1.27)
				)
				(justify mirror)
			)
		)
		(property "Value" ""
			(at 0 0 0)
			(layer "B.Fab")
			(effects
				(font
					(size 1.27 1.27)
				)
				(justify mirror)
			)
		)
		(duplicate_pad_numbers_are_jumpers no)
		(fp_line
			(start 0.7874 0.4064)
			(end 0.7874 -0.4064)
			(stroke
				(width 0.1524)
				(type default)
			)
			(layer "B.SilkS")
		)
		(fp_line
			(start 0.7874 -0.4064)
			(end -0.7874 -0.4064)
			(stroke
				(width 0.1524)
				(type default)
			)
			(layer "B.SilkS")
		)
		(fp_line
			(start -0.7874 0.4064)
			(end 0.7874 0.4064)
			(stroke
				(width 0.1524)
				(type default)
			)
			(layer "B.SilkS")
		)
		(fp_line
			(start -0.7874 -0.4064)
			(end -0.7874 0.4064)
			(stroke
				(width 0.1524)
				(type default)
			)
			(layer "B.SilkS")
		)
		(fp_line
			(start 0.67945 0.3048)
			(end 0.67945 -0.305054)
			(stroke
				(width 0.1)
				(type default)
			)
			(layer "B.Fab")
		)
		(fp_line
			(start 0.67945 -0.305054)
			(end 0.12065 -0.305054)
			(stroke
				(width 0.1)
				(type default)
			)
			(layer "B.Fab")
		)
		(fp_line
			(start 0.12065 0.3048)
			(end 0.67945 0.3048)
			(stroke
				(width 0.1)
				(type default)
			)
			(layer "B.Fab")
		)
		(fp_line
			(start 0.12065 0.2794)
			(end 0.12065 0.3048)
			(stroke
				(width 0.1)
				(type default)
			)
			(layer "B.Fab")
		)
		(fp_line
			(start 0.12065 -0.2794)
			(end -0.12065 -0.2794)
			(stroke
				(width 0.1)
				(type default)
			)
			(layer "B.Fab")
		)
		(fp_line
			(start 0.12065 -0.305054)
			(end 0.12065 -0.2794)
			(stroke
				(width 0.1)
				(type default)
			)
			(layer "B.Fab")
		)
		(fp_line
			(start -0.120396 0.3048)
			(end -0.120396 0.2794)
			(stroke
				(width 0.1)
				(type default)
			)
			(layer "B.Fab")
		)
		(fp_line
			(start -0.120396 0.2794)
			(end 0.12065 0.2794)
			(stroke
				(width 0.1)
				(type default)
			)
			(layer "B.Fab")
		)
		(fp_line
			(start -0.12065 -0.2794)
			(end -0.12065 -0.3048)
			(stroke
				(width 0.1)
				(type default)
			)
			(layer "B.Fab")
		)
		(fp_line
			(start -0.12065 -0.3048)
			(end -0.67945 -0.3048)
			(stroke
				(width 0.1)
				(type default)
			)
			(layer "B.Fab")
		)
		(fp_line
			(start -0.67945 0.3048)
			(end -0.120396 0.3048)
			(stroke
				(width 0.1)
				(type default)
			)
			(layer "B.Fab")
		)
		(fp_line
			(start -0.67945 -0.3048)
			(end -0.67945 0.3048)
			(stroke
				(width 0.1)
				(type default)
			)
			(layer "B.Fab")
		)
		(pad "1" smd circle
			(at 0.40005 0)
			(size 0 0)
			(layers "B.Cu" "B.Mask" "B.Paste")
			(net "FM_DB2000_VSBEN")
		)
		(pad "2" smd circle
			(at -0.40005 0)
			(size 0 0)
			(layers "B.Cu" "B.Mask" "B.Paste")
			(net "GND")
		)
	)
	(footprint ""
		(layer "B.Cu")
		(at 340.877398 -50.681636 180)
		(property "Reference" "C1266"
			(at 0 0 0)
			(layer "B.SilkS")
			(hide yes)
			(effects
				(font
					(size 1.27 1.27)
				)
				(justify mirror)
			)
		)
		(property "Value" ""
			(at 0 0 0)
			(layer "B.Fab")
			(effects
				(font
					(size 1.27 1.27)
				)
				(justify mirror)
			)
		)
		(duplicate_pad_numbers_are_jumpers no)
		(fp_line
			(start 0.7874 0.4064)
			(end 0.7874 -0.4064)
			(stroke
				(width 0.1524)
				(type default)
			)
			(layer "B.SilkS")
		)
		(fp_line
			(start 0.7874 -0.4064)
			(end -0.7874 -0.4064)
			(stroke
				(width 0.1524)
				(type default)
			)
			(layer "B.SilkS")
		)
		(fp_line
			(start -0.7874 0.4064)
			(end 0.7874 0.4064)
			(stroke
				(width 0.1524)
				(type default)
			)
			(layer "B.SilkS")
		)
		(fp_line
			(start -0.7874 -0.4064)
			(end -0.7874 0.4064)
			(stroke
				(width 0.1524)
				(type default)
			)
			(layer "B.SilkS")
		)
		(fp_line
			(start 0.67945 0.3048)
			(end 0.67945 -0.305054)
			(stroke
				(width 0.1)
				(type default)
			)
			(layer "B.Fab")
		)
		(fp_line
			(start 0.67945 -0.305054)
			(end 0.12065 -0.305054)
			(stroke
				(width 0.1)
				(type default)
			)
			(layer "B.Fab")
		)
		(fp_line
			(start 0.12065 0.3048)
			(end 0.67945 0.3048)
			(stroke
				(width 0.1)
				(type default)
			)
			(layer "B.Fab")
		)
		(fp_line
			(start 0.12065 0.2794)
			(end 0.12065 0.3048)
			(stroke
				(width 0.1)
				(type default)
			)
			(layer "B.Fab")
		)
		(fp_line
			(start 0.12065 -0.2794)
			(end -0.12065 -0.2794)
			(stroke
				(width 0.1)
				(type default)
			)
			(layer "B.Fab")
		)
		(fp_line
			(start 0.12065 -0.305054)
			(end 0.12065 -0.2794)
			(stroke
				(width 0.1)
				(type default)
			)
			(layer "B.Fab")
		)
		(fp_line
			(start -0.120396 0.3048)
			(end -0.120396 0.2794)
			(stroke
				(width 0.1)
				(type default)
			)
			(layer "B.Fab")
		)
		(fp_line
			(start -0.120396 0.2794)
			(end 0.12065 0.2794)
			(stroke
				(width 0.1)
				(type default)
			)
			(layer "B.Fab")
		)
		(fp_line
			(start -0.12065 -0.2794)
			(end -0.12065 -0.3048)
			(stroke
				(width 0.1)
				(type default)
			)
			(layer "B.Fab")
		)
		(fp_line
			(start -0.12065 -0.3048)
			(end -0.67945 -0.3048)
			(stroke
				(width 0.1)
				(type default)
			)
			(layer "B.Fab")
		)
		(fp_line
			(start -0.67945 0.3048)
			(end -0.120396 0.3048)
			(stroke
				(width 0.1)
				(type default)
			)
			(layer "B.Fab")
		)
		(fp_line
			(start -0.67945 -0.3048)
			(end -0.67945 0.3048)
			(stroke
				(width 0.1)
				(type default)
			)
			(layer "B.Fab")
		)
		(pad "1" smd circle
			(at 0.40005 0)
			(size 0 0)
			(layers "B.Cu" "B.Mask" "B.Paste")
			(net "P1V8_PCH_PLL_AUX")
		)
		(pad "2" smd circle
			(at -0.40005 0)
			(size 0 0)
			(layers "B.Cu" "B.Mask" "B.Paste")
			(net "GND")
		)
	)
)
